# T6G (Grand Teton) — schematic netlist excerpt (pin names and nets, part order shuffled) for the footprints in the layout excerpt that follows; sources: Cadence DE-HDL packaged netlist, KiCad conversion of 04192023_DAF0TMB3IC0_F0TG_MB_C_brd_V02_OCP.brd

PC466  Q_CAP  1UF 6.3V 10% X7R  pkg 0402  page 193 : A = PVDD18_S5_P0 ; B = GND
C2452  Q_CAP  22UF 4V 20% X6S  pkg C0402  page 74 : A = PVDDCR_SOC_P1 ; B = GND

(kicad_pcb
	(version 20260206)
	(generator "pcbnew")
	(generator_version "10.0")
	(general
		(thickness 1.6)
		(legacy_teardrops no)
	)
	(paper "A4")
	(title_block
		(title "04192023_DAF0TMB3IC0_F0TG_MB_C_brd_V02_OCP.brd")
		(comment 1 "Grand Teton / footprints 5473-5474 of 8354")
	)
	(layers
		(0 "F.Cu" signal "TOP")
		(4 "In1.Cu" signal "GND")
		(6 "In2.Cu" signal "IN1")
		(8 "In3.Cu" signal "GND1")
		(10 "In4.Cu" signal "IN2")
		(12 "In5.Cu" signal "GND2")
		(14 "In6.Cu" signal "IN3")
		(16 "In7.Cu" signal "GND3")
		(18 "In8.Cu" signal "VCC")
		(20 "In9.Cu" signal "VCC1")
		(22 "In10.Cu" signal "GND4")
		(24 "In11.Cu" signal "IN4")
		(26 "In12.Cu" signal "GND5")
		(28 "In13.Cu" signal "IN5")
		(30 "In14.Cu" signal "GND6")
		(32 "In15.Cu" signal "IN6")
		(34 "In16.Cu" signal "GND7")
		(2 "B.Cu" signal "BOTTOM")
		(9 "F.Adhes" user "F.Adhesive")
		(11 "B.Adhes" user "B.Adhesive")
		(13 "F.Paste" user "Package Geometry/Pastemask Top")
		(15 "B.Paste" user "Package Geometry/Pastemask Bottom")
		(5 "F.SilkS" user "Ref Des/Silkscreen Top")
		(7 "B.SilkS" user "Ref Des/Silkscreen Bottom")
		(1 "F.Mask" user "Board Geometry/Soldermask Top")
		(3 "B.Mask" user "Board Geometry/Soldermask Bottom")
		(17 "Dwgs.User" user "User.Drawings")
		(19 "Cmts.User" user "User.Comments")
		(21 "Eco1.User" user "User.Eco1")
		(23 "Eco2.User" user "User.Eco2")
		(25 "Edge.Cuts" user "Board Geometry/Outline")
		(27 "Margin" user)
		(31 "F.CrtYd" user "Package Geometry/Place Bound Top")
		(29 "B.CrtYd" user "Package Geometry/Place Bound Bottom")
		(35 "F.Fab" user "Ref Des/Assembly Top")
		(33 "B.Fab" user "Ref Des/Assembly Bottom")
	)
	(footprint ""
		(layer "B.Cu")
		(at 125.389386 -254.194564)
		(property "Reference" "C2452"
			(at 0 0 0)
			(layer "B.SilkS")
			(hide yes)
			(effects
				(font
					(size 1.27 1.27)
				)
				(justify mirror)
			)
		)
		(property "Value" ""
			(at 0 0 0)
			(layer "B.Fab")
			(effects
				(font
					(size 1.27 1.27)
				)
				(justify mirror)
			)
		)
		(duplicate_pad_numbers_are_jumpers no)
		(fp_line
			(start -0.7874 -0.4064)
			(end -0.7874 0.4064)
			(stroke
				(width 0.1524)
				(type default)
			)
			(layer "B.SilkS")
		)
		(fp_line
			(start -0.7874 0.4064)
			(end 0.7874 0.4064)
			(stroke
				(width 0.1524)
				(type default)
			)
			(layer "B.SilkS")
		)
		(fp_line
			(start 0.7874 -0.4064)
			(end -0.7874 -0.4064)
			(stroke
				(width 0.1524)
				(type default)
			)
			(layer "B.SilkS")
		)
		(fp_line
			(start 0.7874 0.4064)
			(end 0.7874 -0.4064)
			(stroke
				(width 0.1524)
				(type default)
			)
			(layer "B.SilkS")
		)
		(fp_line
			(start -0.67945 -0.3048)
			(end -0.67945 0.3048)
			(stroke
				(width 0.1)
				(type default)
			)
			(layer "B.Fab")
		)
		(fp_line
			(start -0.67945 0.3048)
			(end -0.120396 0.3048)
			(stroke
				(width 0.1)
				(type default)
			)
			(layer "B.Fab")
		)
		(fp_line
			(start -0.12065 -0.3048)
			(end -0.67945 -0.3048)
			(stroke
				(width 0.1)
				(type default)
			)
			(layer "B.Fab")
		)
		(fp_line
			(start -0.12065 -0.2794)
			(end -0.12065 -0.3048)
			(stroke
				(width 0.1)
				(type default)
			)
			(layer "B.Fab")
		)
		(fp_line
			(start -0.120396 0.2794)
			(end 0.12065 0.2794)
			(stroke
				(width 0.1)
				(type default)
			)
			(layer "B.Fab")
		)
		(fp_line
			(start -0.120396 0.3048)
			(end -0.120396 0.2794)
			(stroke
				(width 0.1)
				(type default)
			)
			(layer "B.Fab")
		)
		(fp_line
			(start 0.12065 -0.305054)
			(end 0.12065 -0.2794)
			(stroke
				(width 0.1)
				(type default)
			)
			(layer "B.Fab")
		)
		(fp_line
			(start 0.12065 -0.2794)
			(end -0.12065 -0.2794)
			(stroke
				(width 0.1)
				(type default)
			)
			(layer "B.Fab")
		)
		(fp_line
			(start 0.12065 0.2794)
			(end 0.12065 0.3048)
			(stroke
				(width 0.1)
				(type default)
			)
			(layer "B.Fab")
		)
		(fp_line
			(start 0.12065 0.3048)
			(end 0.67945 0.3048)
			(stroke
				(width 0.1)
				(type default)
			)
			(layer "B.Fab")
		)
		(fp_line
			(start 0.67945 -0.305054)
			(end 0.12065 -0.305054)
			(stroke
				(width 0.1)
				(type default)
			)
			(layer "B.Fab")
		)
		(fp_line
			(start 0.67945 0.3048)
			(end 0.67945 -0.305054)
			(stroke
				(width 0.1)
				(type default)
			)
			(layer "B.Fab")
		)
		(pad "1" smd circle
			(at 0.40005 0 180)
			(size 0 0)
			(layers "B.Cu" "B.Mask" "B.Paste")
			(net "PVDDCR_SOC_P1")
		)
		(pad "2" smd circle
			(at -0.40005 0 180)
			(size 0 0)
			(layers "B.Cu" "B.Mask" "B.Paste")
			(net "GND")
		)
	)
	(footprint ""
		(layer "B.Cu")
		(at 372.937278 -142.488158)
		(property "Reference" "PC466"
			(at 0 0 0)
			(layer "B.SilkS")
			(hide yes)
			(effects
				(font
					(size 1.27 1.27)
				)
				(justify mirror)
			)
		)
		(property "Value" ""
			(at 0 0 0)
			(layer "B.Fab")
			(effects
				(font
					(size 1.27 1.27)
				)
				(justify mirror)
			)
		)
		(duplicate_pad_numbers_are_jumpers no)
		(fp_line
			(start -0.7874 -0.4064)
			(end -0.7874 0.4064)
			(stroke
				(width 0.1524)
				(type default)
			)
			(layer "B.SilkS")
		)
		(fp_line
			(start -0.7874 0.4064)
			(end 0.7874 0.4064)
			(stroke
				(width 0.1524)
				(type default)
			)
			(layer "B.SilkS")
		)
		(fp_line
			(start 0.7874 -0.4064)
			(end -0.7874 -0.4064)
			(stroke
				(width 0.1524)
				(type default)
			)
			(layer "B.SilkS")
		)
		(fp_line
			(start 0.7874 0.4064)
			(end 0.7874 -0.4064)
			(stroke
				(width 0.1524)
				(type default)
			)
			(layer "B.SilkS")
		)
		(fp_line
			(start -0.67945 -0.3048)
			(end -0.67945 0.3048)
			(stroke
				(width 0.1)
				(type default)
			)
			(layer "B.Fab")
		)
		(fp_line
			(start -0.67945 0.3048)
			(end -0.120396 0.3048)
			(stroke
				(width 0.1)
				(type default)
			)
			(layer "B.Fab")
		)
		(fp_line
			(start -0.12065 -0.3048)
			(end -0.67945 -0.3048)
			(stroke
				(width 0.1)
				(type default)
			)
			(layer "B.Fab")
		)
		(fp_line
			(start -0.12065 -0.2794)
			(end -0.12065 -0.3048)
			(stroke
				(width 0.1)
				(type default)
			)
			(layer "B.Fab")
		)
		(fp_line
			(start -0.120396 0.2794)
			(end 0.12065 0.2794)
			(stroke
				(width 0.1)
				(type default)
			)
			(layer "B.Fab")
		)
		(fp_line
			(start -0.120396 0.3048)
			(end -0.120396 0.2794)
			(stroke
				(width 0.1)
				(type default)
			)
			(layer "B.Fab")
		)
		(fp_line
			(start 0.12065 -0.305054)
			(end 0.12065 -0.2794)
			(stroke
				(width 0.1)
				(type default)
			)
			(layer "B.Fab")
		)
		(fp_line
			(start 0.12065 -0.2794)
			(end -0.12065 -0.2794)
			(stroke
				(width 0.1)
				(type default)
			)
			(layer "B.Fab")
		)
		(fp_line
			(start 0.12065 0.2794)
			(end 0.12065 0.3048)
			(stroke
				(width 0.1)
				(type default)
			)
			(layer "B.Fab")
		)
		(fp_line
			(start 0.12065 0.3048)
			(end 0.67945 0.3048)
			(stroke
				(width 0.1)
				(type default)
			)
			(layer "B.Fab")
		)
		(fp_line
			(start 0.67945 -0.305054)
			(end 0.12065 -0.305054)
			(stroke
				(width 0.1)
				(type default)
			)
			(layer "B.Fab")
		)
		(fp_line
			(start 0.67945 0.3048)
			(end 0.67945 -0.305054)
			(stroke
				(width 0.1)
				(type default)
			)
			(layer "B.Fab")
		)
		(pad "1" smd circle
			(at 0.40005 0 180)
			(size 0 0)
			(layers "B.Cu" "B.Mask" "B.Paste")
			(net "PVDD18_S5_P0")
		)
		(pad "2" smd circle
			(at -0.40005 0 180)
			(size 0 0)
			(layers "B.Cu" "B.Mask" "B.Paste")
			(net "GND")
		)
	)
)
